# BASEBOARD_FAB2 (Tioga Pass) — schematic netlist excerpt (pin names and nets, part order shuffled) for the footprints in the layout excerpt that follows; sources: Cadence DE-HDL packaged netlist, KiCad conversion of Wiwynn_Tioga_Pass_MB.brd

U8D7  LCMXO2_A  IC  pkg 256BGA  page 190
  VCC(0)  = P3V3_STBY
  NC(0)  = NC
  PT11C  = FM_PCH_PRSNT_N
  PT10A  = FM_P3V3_CPLD_EN
  PT11A  = TP_CPLD1_PT11A
  PT12D_TDI  = JTAG_PLD_TDI
  PT16C_TCK  = JTAG_PLD_TCK
  PT17B_PCLKC0_1  = TP_CPLD1_PT17B_PCLKC0_1
  PT18C_SCL_PCLKT0_0  = SMB_SENSOR_STBY_LVC3_SCL
  PT19B  = FM_PVCCIN_PVCCSA_CPU0_EN_LVC1
  PT21A  = FM_CPU0_OR_CPU1_MCP_PRES
  PT22B  = PU_THERMTRIP_FORCE_N
  PT24C_INITN  = TP_CPLD1_PT24C_INITN
  PT22D  = TP_CPLD1_PT22D
  PT24B  = TP_CPLD1_PT24B
  VCC(1)  = P3V3_STBY
  PL1C  = RST_PCIE_PCH_PERST_N
  GND(0)  = GND
  PT9C  = FM_CTNR_PS_ON
  PT11D  = PWRGD_PVTT_CPU0
  PT9B  = PWRGD_P12V_MAIN
  PT11B  = TP_CPLD1_PT11B
  PT13A  = TP_CPLD1_PT13A
  PT16D_TMS  = JTAG_PLD_TMS
  PT19A  = PU_RST_PERST_BIT1
  PT20D_PROGRAMN  = PU_CPLD1_PT20D_PROGRAMN
  PT22A  = PWRGD_DSW_PWROK
  PT23B  = FM_PCH_PWRBTN_R1_N
  PT22C  = TP_CPLD1_PT22C
  PT24A  = FM_SINT_PRSNT_N
  GND(1)  = GND
  PR1D  = FM_ADR_COMPLETE_DLY
  PL2C  = RST_PCIE_CPU_DEV1_N
  PL1D  = FM_PCH_PLD_DATA
  GND(2)  = GND
  PT9A  = FM_ADR_SMI_GPIO_R_N
  PT10B  = FM_CPU1_THERMTRIP_LATCH_LVT3_N
  PT12C_TDO  = JTAG_PLD_TDO
  PT13B  = FM_BMC_ONCTL_N
  PT17A_PCLKT0_1  = FM_ADR_COMPLETE
  PT18D_SDA_PCLKC0_0  = SMB_SENSOR_STBY_LVC3_SDA
  PT20C_JTAGENB  = FM_JTAG_PLD_EN_DEBUG
  PT21B  = FM_CPU0_CD_PRES
  PT23A  = FM_SLPS4_N
  PT24D_DONE  = TP_CPLD1_PT24D_DONE
  GND(3)  = GND
  PR1C  = FM_DB1200_PWRGD
  PR2C  = PWRGD_PCH_PWROK
  PL1B_L_GPLLC_FB  = TP_CPLD1_PL1B_L_GPLLC_FB
  PL2D  = FM_MEM_EVENT_FUNC
  PL1A_L_GPLLT_FB  = TP_CPLD1_PL1A_L_GPLLT_FB
  GND(4)  = GND
  VCCIO0(3)  = P3V3_STBY
  PT12A  = RST_PCIE_CPU_DEV0_N
  PT13D  = FM_FORCE_ADR_N
  PT17C  = TP_CPLD1_PT17C
  PT18B  = RST_PCIE_MIDPLANE_N
  PT20A  = TP_CPLD1_PT20A
  PT21D  = FM_CPU0_AND_CPU1_MCP_PRES
  VCCIO0(1)  = P3V3_STBY
  GND(5)  = GND
  PR1A  = PWRGD_SYS_PWROK
  PR2D  = PWRGD_P1V8MCP_CPU0
  PR2A  = PWRGD_P1V8MCP_CPU1
  PL3A_PCLKT5_0  = CLK_32K_SUSCLK_PLD
  PL2A_L_GPLLT_IN  = FM_CPU_CATERR_DLY_LVT3_N
  PL2B_L_GPLLC_IN  = TP_CPLD1_PL2B_L_GPLLC_IN
  VCCIO5(0)  = P3V3_STBY
  GND(6)  = GND
  PT13C  = FM_CPU1_FIVR_FAULT_LVT3_N
  PT12B  = PWRGD_P1V15_BMC_STBY
  PT16B  = TP_CPLD1_PT16B
  PT17D  = FM_SLP_SUS_N
  PT20B  = TP_CPLD1_PT20B
  PT19D  = TP_CPLD1_PT19D
  GND(7)  = GND
  VCCIO1(0)  = P3V3_STBY
  PR2B  = FM_CPLD_ADR_TRIGGER_N
  PR1B  = RST_PLTRST_N
  PR3A  = FM_P1V8MCP_CPU0_EN
  PL4B  = FM_CPU0_PROC_ID0
  PL3B_PCLKC5_0  = FM_CPU0_PKGID0
  PL4A  = FM_CPU0_PROC_ID1
  PL3C  = PU_RST_PERST_BIT0
  PL5C  = FM_CPU0_FIVR_FAULT_LVT3_N
  GND(8)  = GND
  PT16A  = FM_PLD_DEBUG_MODE_N
  PT18A  = SGPIO_BMC_DIN_R
  PT19C  = FM_PS_EN
  PT21C  = FM_CPU1_CD_PRES_N
  GND(9)  = GND
  PR4C  = FM_P1V8MCP_CPU1_EN
  PR3C  = PWRGD_CPUPWRGD
  PR4A  = RST_BMC_SYSRST_BTN_OUT_B_R1_N
  PR3B  = FM_CPU0_MCP_CLK_EN_N
  PR4B  = FM_CPU1_MCP_CLK_EN_N
  PL6A  = FM_SLPS3_N
  PL5A  = FM_CPU0_PKGID2
  PL5B  = FM_CPU0_PKGID1
  PL4D  = RST_RSMRST_R_N
  PL4C  = FM_DEBUG_RST_BTN_N
  PL3D  = FM_PWR_BTN_R2_N
  VCC(4)  = P3V3_STBY
  VCCIO0(0)  = P3V3_STBY
  VCCIO0(2)  = P3V3_STBY
  VCC(5)  = P3V3_STBY
  PR5C  = FM_WBG_PRSNT_N
  PR3D  = FM_CPU0_THERMTRIP_LATCH_LVT3_N
  PR4D  = FM_CPU1_FIVR_FAULT_LVT3
  PR5B  = FM_CPU1_THERMTRIP_LVT3_N
  PR5A  = FM_UV_ADR_TRIGGER_N
  PR6A  = FM_FAST_PROCHOT_THROTTLE_IN_N
  PL7B  = RST_PCIE_CPU_DEV3_N
  PL6B  = FM_PVCCMCP_CPU0_EN
  PL7A  = RST_PCIE_CPU_DEV2_N
  PL6C  = FM_MP_PS_FAIL_N
  PL9C  = NC
  PL5D  = PWRGD_P3V3
  VCCIO4(1)  = P3V3_STBY
  GND(10)  = GND
  GND(11)  = GND
  VCCIO1(1)  = P3V3_STBY
  PR9C  = TP_CPLD1_PR9C
  PR5D  = FM_UV_ADR_TRIGGER_EN
  PR6C  = FM_PVDDQ_GHJ_EN
  PR7A_PCLKT1_0  = TP_CPLD1_PR7A_PCLKT1_0
  PR6B  = FM_PVDDQ_KLM_EN
  PR7B_PCLKC1_0  = TP_CPLD1_PR7B_PCLKC1_0
  PL7C_PCLKT4_0  = SGPIO_BMC_CLK
  PL9A  = SGPIO_BMC_DOUT
  PL7D_PCLKC4_0  = TP_CPLD1_PL7D_PCLKT4_0
  PL9D  = NC
  PL10C  = UART_BMC_RXD5
  PL6D  = PWRGD_P5V
  VCCIO4(0)  = P3V3_STBY
  GND(12)  = GND
  GND(13)  = GND
  VCCIO1(2)  = P3V3_STBY
  PR10C  = TP_CPLD1_PR10C
  PR6D  = FM_FAST_PROCHOT_THROTTLE_DLY_N
  PR9D  = TP_CPLD1_PR9D
  PR7D  = TP_CPLD1_PR7D
  PR9A  = TP_CPLD1_PR9A
  PR7C  = TP_CPLD1_PR7C
  PL9B  = FM_PVCCIOMCP_CPU0_EN
  PL10B  = SP1_BMC_HOST_UART_TX
  PL10A  = SP1_BMC_HOST_UART_RX
  PL11C  = SGPIO_BMC_LD_N
  PL12C  = PWRGD_PVCCIN_CPU0
  PL10D  = UART_BMC_TXD5
  VCC(6)  = P3V3_STBY
  VCCIO2(2)  = P3V3_STBY
  VCCIO2(0)  = P3V3_STBY
  VCC(7)  = P3V3_STBY
  PR12C  = RST_PLTRST_BUF_N
  PR11D  = FM_MEM_THERM_EVENT_PCH_N
  PR11C  = FM_MEM_THERM_EVENT_LVT3_N
  PR10A  = FM_PVDDQ_ABC_EN
  PR10B  = FM_PVDDQ_DEF_EN
  PR9B  = PU_FAB2_MARKER_CPLD
  PL11A  = PWRGD_PVSA_CPU0
  PL12A_PCLKT3_0  = CLK_25M_CPLD
  PL11B  = TP_CPLD1_PL11A
  PL12D  = PWRGD_PVCCMCP_CPU1
  PL11D  = PWRGD_CPU0_LVC3
  GND(14)  = GND
  PB8D  = FM_OC0_USB_N
  PB11D  = PWRGD_PVCCIO_CPU0
  PB12D  = FM_IE_DISABLE_N
  PB18D  = FM_SOL_UART_CH_SEL
  GND(15)  = GND
  PR10D  = PWRGD_P3V3_STBY
  PR12D  = TP_CPLD1_PR12D
  PR11B  = TP_CPLD1_PR11B
  PR12A  = FM_THERMTRIP_DLY
  PR11A  = PWRGD_PVCCIO_CPU1
  PL12B_PCLKC3_0  = RST_RSMRST_DLY
  PL14A  = PWRGD_PVPP_GHJ
  PL13A  = RST_PCIE_RISER1_PERST_N
  VCCIO3(0)  = P3V3_STBY
  GND(16)  = GND
  PB11C  = PWRGD_PVPP_DEF
  PB9C  = FM_PVCCIO_CPU0_EN
  PB16C  = FM_PVCCMCP_CPU1_EN
  PB18C  = FM_CPLD_UART_CH_LOCK_N
  PB21C  = PWRGD_CPU1_LVC3
  PB19D  = XDP_PWRGD_RST_N
  GND(17)  = GND
  VCCIO1(3)  = P3V3_STBY
  PR13A  = FM_CPU1_PROC_ID1
  PR13B  = FM_CPU1_PROC_ID0
  PR12B  = FM_CPU0_FIVR_FAULT_LVT3
  PL13B  = PWRGD_PVCCIN_CPU1
  PL13C  = PWRGD_PVPP_KLM
  PL14B  = RST_CD_CPU0_POR_N
  GND(18)  = GND
  VCCIO2(3)  = P3V3_STBY
  PB8C  = PWRGD_PVCCIOMCP_CPU0
  PB9D  = PWRGD_PVPP_ABC
  PB12C  = FM_156M_CPU1_BRD_OSC_EN
  PB16D  = FM_CPLD_BMC_PWRDN_N
  PB19C  = RST_CPU1_LVC3_R1_N
  PB21D  = XDP_SYSPWROK
  VCCIO2(1)  = P3V3_STBY
  GND(19)  = GND
  PR14B  = FM_CPU1_VRM_OSC_EN
  PR13C  = FM_CPU0_THERMTRIP_LVT3_N
  PR14A  = FM_PVCCIN_PVCCSA_CPU1_EN_LVC1
  PL13D  = FM_GLOBAL_RST_WARN_N
  PL14D  = FM_UART_ALERT_N
  GND(20)  = GND
  PB3A  = FM_CPU1_RC_EN
  PB5B  = PWRGD_PVCCMCP_CPU0
  PB8A_MCLK_CCLK  = TP_CPLD1_PB8A_MCLK_CCLK
  PB9B  = FM_PVCCIOMCP_CPU1_EN
  PB12A  = PWRGD_PVNN_P1V05_PCH
  PB16B_PCLKC2_1  = TP_CPLD1_PB16B_PCLKC2_1
  PB19A  = RST_CD_CPU1_POR_N
  PB21B  = FM_UARTSW_MSB_N
  PB24A  = FM_CPU1_PKGID1
  PB25B_SI_SISPI  = TP_CPLD1_PB25B_SI_SISPI
  GND(21)  = GND
  PR14C  = FM_PVPP_CPU0_EN
  PR13D  = FM_PVPP_CPU1_EN
  PL14C  = FM_BMC_CPLD_GPO
  GND(22)  = GND
  PB3D  = FM_CPU0_RC_EN
  PB6D  = FM_BMC_CPLD_MP_RST_N
  PB5A_CSSPIN  = TP_CPLD1_PB5A_CSSPIN
  PB6B  = RST_PCIE_M2_DEV_N
  PB9A  = PWRGD_PVTT_CPU1
  PB11B_PCLKC2_0  = FM_CPLD_USB_P0_EN_N
  PB18A  = FM_UARTSW_LSB_N
  PB19B  = RST_CPU0_LVC3_R1_N
  PB22A  = FM_DB1200ZL_BCLKS_EN_N
  PB25A_SN  = FM_CPU1_PKGID0
  PB22C  = FM_CPU0_VRM_OSC_EN
  PB25D  = FM_CPU_CATERR_LVT3_N
  GND(23)  = GND
  PR14D  = FM_P12V_MAIN_SW_EN
  VCC(2)  = P3V3_STBY
  PB3C  = FM_ADR_MODE_SEL
  PB6C  = FM_DIS_ADR_DLY
  PB3B  = PWRGD_PVSA_CPU1
  PB6A  = PWRGD_PVCCIOMCP_CPU1
  PB8B_SO_SPISO  = TP_CPLD1_PB8B_SO_SPISO
  PB11A_PCLKT2_0  = FM_PVCCIO_CPU1_EN
  PB12B  = FM_CPLD_DBG_PWR_EN_N
  PB16A_PCLKT2_1  = TP_CPLD1_PB16A_PCLKT2_1
  PB18B  = FM_156M_CPU0_BRD_OSC_EN
  PB21A  = FM_CPU1_PKGID2
  PB22B  = FM_CPU1_SKTOCC_LVT3_N
  PB24B  = FM_CPU_MSMI_LVT3_N
  PB22D  = FM_CPU0_SKTOCC_LVT3_N
  PB25C  = PWRGD_DRAMPWRGD
  VCC(3)  = P3V3_STBY

(kicad_pcb
	(version 20260206)
	(generator "pcbnew")
	(generator_version "10.0")
	(general
		(thickness 1.6)
		(legacy_teardrops no)
	)
	(paper "A4")
	(title_block
		(title "Wiwynn_Tioga_Pass_MB.brd")
		(comment 1 "Tioga Pass / footprint 2035 of 4770 (U8D7), pads 135-180 of 256")
	)
	(layers
		(0 "F.Cu" signal "TOP")
		(4 "In1.Cu" signal "L2GND")
		(6 "In2.Cu" signal "L3")
		(8 "In3.Cu" signal "L4GND")
		(10 "In4.Cu" signal "L5")
		(12 "In5.Cu" signal "L6GND")
		(14 "In6.Cu" signal "L7VCC")
		(16 "In7.Cu" signal "L8VCC")
		(18 "In8.Cu" signal "L9GND")
		(20 "In9.Cu" signal "L10")
		(22 "In10.Cu" signal "L11GND")
		(24 "In11.Cu" signal "L12")
		(26 "In12.Cu" signal "L13GND")
		(2 "B.Cu" signal "BOTTOM")
		(9 "F.Adhes" user "F.Adhesive")
		(11 "B.Adhes" user "B.Adhesive")
		(13 "F.Paste" user "Package Geometry/Pastemask Top")
		(15 "B.Paste" user "Package Geometry/Pastemask Bottom")
		(5 "F.SilkS" user "Ref Des/Silkscreen Top")
		(7 "B.SilkS" user "Ref Des/Silkscreen Bottom")
		(1 "F.Mask" user "Board Geometry/Soldermask Top")
		(3 "B.Mask" user "Board Geometry/Soldermask Bottom")
		(17 "Dwgs.User" user "User.Drawings")
		(19 "Cmts.User" user "User.Comments")
		(21 "Eco1.User" user "User.Eco1")
		(23 "Eco2.User" user "User.Eco2")
		(25 "Edge.Cuts" user "Board Geometry/Outline")
		(27 "Margin" user)
		(31 "F.CrtYd" user "Package Geometry/Place Bound Top")
		(29 "B.CrtYd" user "Package Geometry/Place Bound Bottom")
		(35 "F.Fab" user "Ref Des/Assembly Top")
		(33 "B.Fab" user "Ref Des/Assembly Bottom")
	)
	(footprint ""
		(layer "F.Cu")
		(at 372.745 -74.295 180)
		(property "Reference" "U8D7"
			(at -0.635 -8.28167 0)
			(unlocked yes)
			(layer "F.SilkS")
			(effects
				(font
					(size 0.7874 0.5842)
					(thickness 0.1524)
				)
			)
		)
		(property "Value" ""
			(at 0 0 180)
			(layer "F.Fab")
			(effects
				(font
					(size 1.27 1.27)
				)
			)
		)
		(duplicate_pad_numbers_are_jumpers no)
		(pad "J7" smd circle
			(at -1.199896 0.40005 180)
			(size 0.3556 0.3556)
			(layers "F.Cu" "F.Mask" "F.Paste")
			(net "P3V3_STBY")
		)
		(pad "J8" smd circle
			(at -0.40005 0.40005 180)
			(size 0.3556 0.3556)
			(layers "F.Cu" "F.Mask" "F.Paste")
			(net "GND")
		)
		(pad "J9" smd circle
			(at 0.40005 0.40005 180)
			(size 0.3556 0.3556)
			(layers "F.Cu" "F.Mask" "F.Paste")
			(net "GND")
		)
		(pad "J10" smd circle
			(at 1.199896 0.40005 180)
			(size 0.3556 0.3556)
			(layers "F.Cu" "F.Mask" "F.Paste")
			(net "P3V3_STBY")
		)
		(pad "J11" smd circle
			(at 1.999996 0.40005 180)
			(size 0.3556 0.3556)
			(layers "F.Cu" "F.Mask" "F.Paste")
			(net "TP_CPLD1_PR10C")
		)
		(pad "J12" smd circle
			(at 2.800096 0.40005 180)
			(size 0.3556 0.3556)
			(layers "F.Cu" "F.Mask" "F.Paste")
			(net "FM_FAST_PROCHOT_THROTTLE_DLY_N")
		)
		(pad "J13" smd circle
			(at 3.599942 0.40005 180)
			(size 0.3556 0.3556)
			(layers "F.Cu" "F.Mask" "F.Paste")
			(net "TP_CPLD1_PR9D")
		)
		(pad "J14" smd circle
			(at 4.400042 0.40005 180)
			(size 0.3556 0.3556)
			(layers "F.Cu" "F.Mask" "F.Paste")
			(net "TP_CPLD1_PR7D")
		)
		(pad "J15" smd circle
			(at 5.199888 0.40005 180)
			(size 0.3556 0.3556)
			(layers "F.Cu" "F.Mask" "F.Paste")
			(net "TP_CPLD1_PR9A")
		)
		(pad "J16" smd circle
			(at 5.999988 0.40005 180)
			(size 0.3556 0.3556)
			(layers "F.Cu" "F.Mask" "F.Paste")
			(net "TP_CPLD1_PR7C")
		)
		(pad "K1" smd circle
			(at -5.999988 1.199896 180)
			(size 0.3556 0.3556)
			(layers "F.Cu" "F.Mask" "F.Paste")
			(net "FM_PVCCIOMCP_CPU0_EN")
		)
		(pad "K2" smd circle
			(at -5.199888 1.199896 180)
			(size 0.3556 0.3556)
			(layers "F.Cu" "F.Mask" "F.Paste")
			(net "SP1_BMC_HOST_UART_TX")
		)
		(pad "K3" smd circle
			(at -4.400042 1.199896 180)
			(size 0.3556 0.3556)
			(layers "F.Cu" "F.Mask" "F.Paste")
			(net "SP1_BMC_HOST_UART_RX")
		)
		(pad "K4" smd circle
			(at -3.599942 1.199896 180)
			(size 0.3556 0.3556)
			(layers "F.Cu" "F.Mask" "F.Paste")
			(net "SGPIO_BMC_LD_N")
		)
		(pad "K5" smd circle
			(at -2.800096 1.199896 180)
			(size 0.3556 0.3556)
			(layers "F.Cu" "F.Mask" "F.Paste")
			(net "PWRGD_PVCCIN_CPU0")
		)
		(pad "K6" smd circle
			(at -1.999996 1.199896 180)
			(size 0.3556 0.3556)
			(layers "F.Cu" "F.Mask" "F.Paste")
			(net "UART_BMC_TXD5")
		)
		(pad "K7" smd circle
			(at -1.199896 1.199896 180)
			(size 0.3556 0.3556)
			(layers "F.Cu" "F.Mask" "F.Paste")
			(net "P3V3_STBY")
		)
		(pad "K8" smd circle
			(at -0.40005 1.199896 180)
			(size 0.3556 0.3556)
			(layers "F.Cu" "F.Mask" "F.Paste")
			(net "P3V3_STBY")
		)
		(pad "K9" smd circle
			(at 0.40005 1.199896 180)
			(size 0.3556 0.3556)
			(layers "F.Cu" "F.Mask" "F.Paste")
			(net "P3V3_STBY")
		)
		(pad "K10" smd circle
			(at 1.199896 1.199896 180)
			(size 0.3556 0.3556)
			(layers "F.Cu" "F.Mask" "F.Paste")
			(net "P3V3_STBY")
		)
		(pad "K11" smd circle
			(at 1.999996 1.199896 180)
			(size 0.3556 0.3556)
			(layers "F.Cu" "F.Mask" "F.Paste")
			(net "RST_PLTRST_BUF_N")
		)
		(pad "K12" smd circle
			(at 2.800096 1.199896 180)
			(size 0.3556 0.3556)
			(layers "F.Cu" "F.Mask" "F.Paste")
			(net "FM_MEM_THERM_EVENT_PCH_N")
		)
		(pad "K13" smd circle
			(at 3.599942 1.199896 180)
			(size 0.3556 0.3556)
			(layers "F.Cu" "F.Mask" "F.Paste")
			(net "FM_MEM_THERM_EVENT_LVT3_N")
		)
		(pad "K14" smd circle
			(at 4.400042 1.199896 180)
			(size 0.3556 0.3556)
			(layers "F.Cu" "F.Mask" "F.Paste")
			(net "FM_PVDDQ_ABC_EN")
		)
		(pad "K15" smd circle
			(at 5.199888 1.199896 180)
			(size 0.3556 0.3556)
			(layers "F.Cu" "F.Mask" "F.Paste")
			(net "FM_PVDDQ_DEF_EN")
		)
		(pad "K16" smd circle
			(at 5.999988 1.199896 180)
			(size 0.3556 0.3556)
			(layers "F.Cu" "F.Mask" "F.Paste")
			(net "PU_FAB2_MARKER_CPLD")
		)
		(pad "L1" smd circle
			(at -5.999988 1.999996 180)
			(size 0.3556 0.3556)
			(layers "F.Cu" "F.Mask" "F.Paste")
			(net "PWRGD_PVSA_CPU0")
		)
		(pad "L2" smd circle
			(at -5.199888 1.999996 180)
			(size 0.3556 0.3556)
			(layers "F.Cu" "F.Mask" "F.Paste")
			(net "CLK_25M_CPLD")
		)
		(pad "L3" smd circle
			(at -4.400042 1.999996 180)
			(size 0.3556 0.3556)
			(layers "F.Cu" "F.Mask" "F.Paste")
			(net "TP_CPLD1_PL11A")
		)
		(pad "L4" smd circle
			(at -3.599942 1.999996 180)
			(size 0.3556 0.3556)
			(layers "F.Cu" "F.Mask" "F.Paste")
			(net "PWRGD_PVCCMCP_CPU1")
		)
		(pad "L5" smd circle
			(at -2.800096 1.999996 180)
			(size 0.3556 0.3556)
			(layers "F.Cu" "F.Mask" "F.Paste")
			(net "PWRGD_CPU0_LVC3")
		)
		(pad "L6" smd circle
			(at -1.999996 1.999996 180)
			(size 0.3556 0.3556)
			(layers "F.Cu" "F.Mask" "F.Paste")
			(net "GND")
		)
		(pad "L7" smd circle
			(at -1.199896 1.999996 180)
			(size 0.3556 0.3556)
			(layers "F.Cu" "F.Mask" "F.Paste")
			(net "FM_OC0_USB_N")
		)
		(pad "L8" smd circle
			(at -0.40005 1.999996 180)
			(size 0.3556 0.3556)
			(layers "F.Cu" "F.Mask" "F.Paste")
			(net "PWRGD_PVCCIO_CPU0")
		)
		(pad "L9" smd circle
			(at 0.40005 1.999996 180)
			(size 0.3556 0.3556)
			(layers "F.Cu" "F.Mask" "F.Paste")
			(net "FM_IE_DISABLE_N")
		)
		(pad "L10" smd circle
			(at 1.199896 1.999996 180)
			(size 0.3556 0.3556)
			(layers "F.Cu" "F.Mask" "F.Paste")
			(net "FM_SOL_UART_CH_SEL")
		)
		(pad "L11" smd circle
			(at 1.999996 1.999996 180)
			(size 0.3556 0.3556)
			(layers "F.Cu" "F.Mask" "F.Paste")
			(net "GND")
		)
		(pad "L12" smd circle
			(at 2.800096 1.999996 180)
			(size 0.3556 0.3556)
			(layers "F.Cu" "F.Mask" "F.Paste")
			(net "PWRGD_P3V3_STBY")
		)
		(pad "L13" smd circle
			(at 3.599942 1.999996 180)
			(size 0.3556 0.3556)
			(layers "F.Cu" "F.Mask" "F.Paste")
			(net "TP_CPLD1_PR12D")
		)
		(pad "L14" smd circle
			(at 4.400042 1.999996 180)
			(size 0.3556 0.3556)
			(layers "F.Cu" "F.Mask" "F.Paste")
			(net "TP_CPLD1_PR11B")
		)
		(pad "L15" smd circle
			(at 5.199888 1.999996 180)
			(size 0.3556 0.3556)
			(layers "F.Cu" "F.Mask" "F.Paste")
			(net "FM_THERMTRIP_DLY")
		)
		(pad "L16" smd circle
			(at 5.999988 1.999996 180)
			(size 0.3556 0.3556)
			(layers "F.Cu" "F.Mask" "F.Paste")
			(net "PWRGD_PVCCIO_CPU1")
		)
		(pad "M1" smd circle
			(at -5.999988 2.800096 180)
			(size 0.3556 0.3556)
			(layers "F.Cu" "F.Mask" "F.Paste")
			(net "RST_RSMRST_DLY")
		)
		(pad "M2" smd circle
			(at -5.199888 2.800096 180)
			(size 0.3556 0.3556)
			(layers "F.Cu" "F.Mask" "F.Paste")
			(net "PWRGD_PVPP_GHJ")
		)
		(pad "M3" smd circle
			(at -4.400042 2.800096 180)
			(size 0.3556 0.3556)
			(layers "F.Cu" "F.Mask" "F.Paste")
			(net "RST_PCIE_RISER1_PERST_N")
		)
		(pad "M4" smd circle
			(at -3.599942 2.800096 180)
			(size 0.3556 0.3556)
			(layers "F.Cu" "F.Mask" "F.Paste")
			(net "P3V3_STBY")
		)
	)
)
